(kicad_pcb
	(version 20260206)
	(generator "pcbnew")
	(generator_version "10.0")
	(general
		(thickness 1.6)
		(legacy_teardrops no)
	)
	(paper "A4")
	(title_block
		(title "04192023_DAF0TMB3IC0_F0TG_MB_C_brd_V02_OCP.brd")
		(comment 1 "Grand Teton / footprints 5479-5487 of 8354")
	)
	(layers
		(0 "F.Cu" signal "TOP")
		(4 "In1.Cu" signal "GND")
		(6 "In2.Cu" signal "IN1")
		(8 "In3.Cu" signal "GND1")
		(10 "In4.Cu" signal "IN2")
		(12 "In5.Cu" signal "GND2")
		(14 "In6.Cu" signal "IN3")
		(16 "In7.Cu" signal "GND3")
		(18 "In8.Cu" signal "VCC")
		(20 "In9.Cu" signal "VCC1")
		(22 "In10.Cu" signal "GND4")
		(24 "In11.Cu" signal "IN4")
		(26 "In12.Cu" signal "GND5")
		(28 "In13.Cu" signal "IN5")
		(30 "In14.Cu" signal "GND6")
		(32 "In15.Cu" signal "IN6")
		(34 "In16.Cu" signal "GND7")
		(2 "B.Cu" signal "BOTTOM")
		(9 "F.Adhes" user "F.Adhesive")
		(11 "B.Adhes" user "B.Adhesive")
		(13 "F.Paste" user "Package Geometry/Pastemask Top")
		(15 "B.Paste" user "Package Geometry/Pastemask Bottom")
		(5 "F.SilkS" user "Ref Des/Silkscreen Top")
		(7 "B.SilkS" user "Ref Des/Silkscreen Bottom")
		(1 "F.Mask" user "Board Geometry/Soldermask Top")
		(3 "B.Mask" user "Board Geometry/Soldermask Bottom")
		(17 "Dwgs.User" user "User.Drawings")
		(19 "Cmts.User" user "User.Comments")
		(21 "Eco1.User" user "User.Eco1")
		(23 "Eco2.User" user "User.Eco2")
		(25 "Edge.Cuts" user "Board Geometry/Outline")
		(27 "Margin" user)
		(31 "F.CrtYd" user "Package Geometry/Place Bound Top")
		(29 "B.CrtYd" user "Package Geometry/Place Bound Bottom")
		(35 "F.Fab" user "Ref Des/Assembly Top")
		(33 "B.Fab" user "Ref Des/Assembly Bottom")
	)
	(footprint ""
		(layer "B.Cu")
		(at 345.645994 -396.393162 -90)
		(property "Reference" "C606"
			(at 0 0 90)
			(layer "B.SilkS")
			(hide yes)
			(effects
				(font
					(size 1.27 1.27)
				)
				(justify mirror)
			)
		)
		(property "Value" ""
			(at 0 0 90)
			(layer "B.Fab")
			(effects
				(font
					(size 1.27 1.27)
				)
				(justify mirror)
			)
		)
		(duplicate_pad_numbers_are_jumpers no)
		(fp_line
			(start -0.299974 0.150114)
			(end 0.299974 0.150114)
			(stroke
				(width 0.1)
				(type default)
			)
			(layer "B.Fab")
		)
		(fp_line
			(start 0.299974 0.150114)
			(end 0.299974 -0.150114)
			(stroke
				(width 0.1)
				(type default)
			)
			(layer "B.Fab")
		)
		(fp_line
			(start -0.299974 -0.150114)
			(end -0.299974 0.150114)
			(stroke
				(width 0.1)
				(type default)
			)
			(layer "B.Fab")
		)
		(fp_line
			(start 0.299974 -0.150114)
			(end -0.299974 -0.150114)
			(stroke
				(width 0.1)
				(type default)
			)
			(layer "B.Fab")
		)
		(pad "1" smd rect
			(at 0.2667 0 90)
			(size 0.3048 0.381)
			(layers "B.Cu" "B.Mask" "B.Paste")
			(net "P1V8_CPU0_RT1_1A")
		)
		(pad "2" smd rect
			(at -0.2667 0 90)
			(size 0.3048 0.381)
			(layers "B.Cu" "B.Mask" "B.Paste")
			(net "GND")
		)
	)
	(footprint ""
		(layer "B.Cu")
		(at 59.428126 -192.66027)
		(property "Reference" "C174"
			(at 0 0 0)
			(layer "B.SilkS")
			(hide yes)
			(effects
				(font
					(size 1.27 1.27)
				)
				(justify mirror)
			)
		)
		(property "Value" ""
			(at 0 0 0)
			(layer "B.Fab")
			(effects
				(font
					(size 1.27 1.27)
				)
				(justify mirror)
			)
		)
		(duplicate_pad_numbers_are_jumpers no)
		(fp_line
			(start -1.524 -0.762)
			(end -1.524 0.762)
			(stroke
				(width 0.1524)
				(type default)
			)
			(layer "B.SilkS")
		)
		(fp_line
			(start -1.524 0.762)
			(end 1.524 0.762)
			(stroke
				(width 0.1524)
				(type default)
			)
			(layer "B.SilkS")
		)
		(fp_line
			(start 1.524 -0.762)
			(end -1.524 -0.762)
			(stroke
				(width 0.1524)
				(type default)
			)
			(layer "B.SilkS")
		)
		(fp_line
			(start 1.524 0.762)
			(end 1.524 -0.762)
			(stroke
				(width 0.1524)
				(type default)
			)
			(layer "B.SilkS")
		)
		(fp_line
			(start -1.1049 -0.724916)
			(end 1.1049 -0.724916)
			(stroke
				(width 0.1)
				(type default)
			)
			(layer "B.Fab")
		)
		(fp_line
			(start -1.1049 0.724916)
			(end -1.1049 -0.724916)
			(stroke
				(width 0.1)
				(type default)
			)
			(layer "B.Fab")
		)
		(fp_line
			(start 1.1049 -0.724916)
			(end 1.1049 0.724916)
			(stroke
				(width 0.1)
				(type default)
			)
			(layer "B.Fab")
		)
		(fp_line
			(start 1.1049 0.724916)
			(end -1.1049 0.724916)
			(stroke
				(width 0.1)
				(type default)
			)
			(layer "B.Fab")
		)
		(pad "1" smd rect
			(at 0.889 0)
			(size 1.016 1.27)
			(layers "B.Cu" "B.Mask" "B.Paste")
			(net "P12V_MEM_CPU1")
		)
		(pad "2" smd rect
			(at -0.889 0)
			(size 1.016 1.27)
			(layers "B.Cu" "B.Mask" "B.Paste")
			(net "GND")
		)
	)
	(footprint ""
		(layer "B.Cu")
		(at 98.046286 -388.011162 -90)
		(property "Reference" "C291"
			(at 0 0 90)
			(layer "B.SilkS")
			(hide yes)
			(effects
				(font
					(size 1.27 1.27)
				)
				(justify mirror)
			)
		)
		(property "Value" ""
			(at 0 0 90)
			(layer "B.Fab")
			(effects
				(font
					(size 1.27 1.27)
				)
				(justify mirror)
			)
		)
		(duplicate_pad_numbers_are_jumpers no)
		(fp_line
			(start -0.299974 0.150114)
			(end 0.299974 0.150114)
			(stroke
				(width 0.1)
				(type default)
			)
			(layer "B.Fab")
		)
		(fp_line
			(start 0.299974 0.150114)
			(end 0.299974 -0.150114)
			(stroke
				(width 0.1)
				(type default)
			)
			(layer "B.Fab")
		)
		(fp_line
			(start -0.299974 -0.150114)
			(end -0.299974 0.150114)
			(stroke
				(width 0.1)
				(type default)
			)
			(layer "B.Fab")
		)
		(fp_line
			(start 0.299974 -0.150114)
			(end -0.299974 -0.150114)
			(stroke
				(width 0.1)
				(type default)
			)
			(layer "B.Fab")
		)
		(pad "1" smd rect
			(at 0.2667 0 90)
			(size 0.3048 0.381)
			(layers "B.Cu" "B.Mask" "B.Paste")
			(net "P0V9_CPU1_RT1_2A")
		)
		(pad "2" smd rect
			(at -0.2667 0 90)
			(size 0.3048 0.381)
			(layers "B.Cu" "B.Mask" "B.Paste")
			(net "GND")
		)
	)
	(footprint ""
		(layer "B.Cu")
		(at 230.886 -330.708 180)
		(property "Reference" "R6779"
			(at 0 0 0)
			(layer "B.SilkS")
			(hide yes)
			(effects
				(font
					(size 1.27 1.27)
				)
				(justify mirror)
			)
		)
		(property "Value" ""
			(at 0 0 0)
			(layer "B.Fab")
			(effects
				(font
					(size 1.27 1.27)
				)
				(justify mirror)
			)
		)
		(duplicate_pad_numbers_are_jumpers no)
		(fp_line
			(start 0.32512 0.175006)
			(end 0.32512 -0.175006)
			(stroke
				(width 0.1)
				(type default)
			)
			(layer "B.Fab")
		)
		(fp_line
			(start 0.32512 -0.175006)
			(end -0.32512 -0.175006)
			(stroke
				(width 0.1)
				(type default)
			)
			(layer "B.Fab")
		)
		(fp_line
			(start -0.32512 0.175006)
			(end 0.32512 0.175006)
			(stroke
				(width 0.1)
				(type default)
			)
			(layer "B.Fab")
		)
		(fp_line
			(start -0.32512 -0.175006)
			(end -0.32512 0.175006)
			(stroke
				(width 0.1)
				(type default)
			)
			(layer "B.Fab")
		)
		(pad "1" smd rect
			(at 0.2667 0)
			(size 0.3048 0.381)
			(layers "B.Cu" "B.Mask" "B.Paste")
			(net "SMB_MUX_RT_SDA")
		)
		(pad "2" smd rect
			(at -0.2667 0 180)
			(size 0.3048 0.381)
			(layers "B.Cu" "B.Mask" "B.Paste")
			(net "SMB_MUX_RT_R1_SDA")
		)
	)
	(footprint ""
		(layer "B.Cu")
		(at 108.625894 -256.012442 -90)
		(property "Reference" "C2417"
			(at 0 0 90)
			(layer "B.SilkS")
			(hide yes)
			(effects
				(font
					(size 1.27 1.27)
				)
				(justify mirror)
			)
		)
		(property "Value" ""
			(at 0 0 90)
			(layer "B.Fab")
			(effects
				(font
					(size 1.27 1.27)
				)
				(justify mirror)
			)
		)
		(duplicate_pad_numbers_are_jumpers no)
		(fp_line
			(start -0.7874 0.4064)
			(end 0.7874 0.4064)
			(stroke
				(width 0.1524)
				(type default)
			)
			(layer "B.SilkS")
		)
		(fp_line
			(start 0.7874 0.4064)
			(end 0.7874 -0.4064)
			(stroke
				(width 0.1524)
				(type default)
			)
			(layer "B.SilkS")
		)
		(fp_line
			(start -0.7874 -0.4064)
			(end -0.7874 0.4064)
			(stroke
				(width 0.1524)
				(type default)
			)
			(layer "B.SilkS")
		)
		(fp_line
			(start 0.7874 -0.4064)
			(end -0.7874 -0.4064)
			(stroke
				(width 0.1524)
				(type default)
			)
			(layer "B.SilkS")
		)
		(fp_line
			(start -0.67945 0.3048)
			(end -0.120396 0.3048)
			(stroke
				(width 0.1)
				(type default)
			)
			(layer "B.Fab")
		)
		(fp_line
			(start -0.120396 0.3048)
			(end -0.120396 0.2794)
			(stroke
				(width 0.1)
				(type default)
			)
			(layer "B.Fab")
		)
		(fp_line
			(start 0.12065 0.3048)
			(end 0.67945 0.3048)
			(stroke
				(width 0.1)
				(type default)
			)
			(layer "B.Fab")
		)
		(fp_line
			(start 0.67945 0.3048)
			(end 0.67945 -0.305054)
			(stroke
				(width 0.1)
				(type default)
			)
			(layer "B.Fab")
		)
		(fp_line
			(start -0.120396 0.2794)
			(end 0.12065 0.2794)
			(stroke
				(width 0.1)
				(type default)
			)
			(layer "B.Fab")
		)
		(fp_line
			(start 0.12065 0.2794)
			(end 0.12065 0.3048)
			(stroke
				(width 0.1)
				(type default)
			)
			(layer "B.Fab")
		)
		(fp_line
			(start -0.12065 -0.2794)
			(end -0.12065 -0.3048)
			(stroke
				(width 0.1)
				(type default)
			)
			(layer "B.Fab")
		)
		(fp_line
			(start 0.12065 -0.2794)
			(end -0.12065 -0.2794)
			(stroke
				(width 0.1)
				(type default)
			)
			(layer "B.Fab")
		)
		(fp_line
			(start -0.67945 -0.3048)
			(end -0.67945 0.3048)
			(stroke
				(width 0.1)
				(type default)
			)
			(layer "B.Fab")
		)
		(fp_line
			(start -0.12065 -0.3048)
			(end -0.67945 -0.3048)
			(stroke
				(width 0.1)
				(type default)
			)
			(layer "B.Fab")
		)
		(fp_line
			(start 0.12065 -0.305054)
			(end 0.12065 -0.2794)
			(stroke
				(width 0.1)
				(type default)
			)
			(layer "B.Fab")
		)
		(fp_line
			(start 0.67945 -0.305054)
			(end 0.12065 -0.305054)
			(stroke
				(width 0.1)
				(type default)
			)
			(layer "B.Fab")
		)
		(pad "1" smd circle
			(at 0.40005 0 90)
			(size 0 0)
			(layers "B.Cu" "B.Mask" "B.Paste")
			(net "PVDDCR_SOC_P1")
		)
		(pad "2" smd circle
			(at -0.40005 0 90)
			(size 0 0)
			(layers "B.Cu" "B.Mask" "B.Paste")
			(net "GND")
		)
	)
	(footprint ""
		(layer "B.Cu")
		(at 100.906834 -249.368564 180)
		(property "Reference" "C2303"
			(at 0 0 0)
			(layer "B.SilkS")
			(hide yes)
			(effects
				(font
					(size 1.27 1.27)
				)
				(justify mirror)
			)
		)
		(property "Value" ""
			(at 0 0 0)
			(layer "B.Fab")
			(effects
				(font
					(size 1.27 1.27)
				)
				(justify mirror)
			)
		)
		(duplicate_pad_numbers_are_jumpers no)
		(fp_line
			(start 0.7874 0.4064)
			(end 0.7874 -0.4064)
			(stroke
				(width 0.1524)
				(type default)
			)
			(layer "B.SilkS")
		)
		(fp_line
			(start 0.7874 -0.4064)
			(end -0.7874 -0.4064)
			(stroke
				(width 0.1524)
				(type default)
			)
			(layer "B.SilkS")
		)
		(fp_line
			(start -0.7874 0.4064)
			(end 0.7874 0.4064)
			(stroke
				(width 0.1524)
				(type default)
			)
			(layer "B.SilkS")
		)
		(fp_line
			(start -0.7874 -0.4064)
			(end -0.7874 0.4064)
			(stroke
				(width 0.1524)
				(type default)
			)
			(layer "B.SilkS")
		)
		(fp_line
			(start 0.67945 0.3048)
			(end 0.67945 -0.305054)
			(stroke
				(width 0.1)
				(type default)
			)
			(layer "B.Fab")
		)
		(fp_line
			(start 0.67945 -0.305054)
			(end 0.12065 -0.305054)
			(stroke
				(width 0.1)
				(type default)
			)
			(layer "B.Fab")
		)
		(fp_line
			(start 0.12065 0.3048)
			(end 0.67945 0.3048)
			(stroke
				(width 0.1)
				(type default)
			)
			(layer "B.Fab")
		)
		(fp_line
			(start 0.12065 0.2794)
			(end 0.12065 0.3048)
			(stroke
				(width 0.1)
				(type default)
			)
			(layer "B.Fab")
		)
		(fp_line
			(start 0.12065 -0.2794)
			(end -0.12065 -0.2794)
			(stroke
				(width 0.1)
				(type default)
			)
			(layer "B.Fab")
		)
		(fp_line
			(start 0.12065 -0.305054)
			(end 0.12065 -0.2794)
			(stroke
				(width 0.1)
				(type default)
			)
			(layer "B.Fab")
		)
		(fp_line
			(start -0.120396 0.3048)
			(end -0.120396 0.2794)
			(stroke
				(width 0.1)
				(type default)
			)
			(layer "B.Fab")
		)
		(fp_line
			(start -0.120396 0.2794)
			(end 0.12065 0.2794)
			(stroke
				(width 0.1)
				(type default)
			)
			(layer "B.Fab")
		)
		(fp_line
			(start -0.12065 -0.2794)
			(end -0.12065 -0.3048)
			(stroke
				(width 0.1)
				(type default)
			)
			(layer "B.Fab")
		)
		(fp_line
			(start -0.12065 -0.3048)
			(end -0.67945 -0.3048)
			(stroke
				(width 0.1)
				(type default)
			)
			(layer "B.Fab")
		)
		(fp_line
			(start -0.67945 0.3048)
			(end -0.120396 0.3048)
			(stroke
				(width 0.1)
				(type default)
			)
			(layer "B.Fab")
		)
		(fp_line
			(start -0.67945 -0.3048)
			(end -0.67945 0.3048)
			(stroke
				(width 0.1)
				(type default)
			)
			(layer "B.Fab")
		)
		(pad "1" smd circle
			(at 0.40005 0)
			(size 0 0)
			(layers "B.Cu" "B.Mask" "B.Paste")
			(net "PVDDCR_CPU0_P1")
		)
		(pad "2" smd circle
			(at -0.40005 0)
			(size 0 0)
			(layers "B.Cu" "B.Mask" "B.Paste")
			(net "GND")
		)
	)
	(footprint ""
		(layer "B.Cu")
		(at 44.14901 -413.691578)
		(property "Reference" "C2073"
			(at 0 0 0)
			(layer "B.SilkS")
			(hide yes)
			(effects
				(font
					(size 1.27 1.27)
				)
				(justify mirror)
			)
		)
		(property "Value" ""
			(at 0 0 0)
			(layer "B.Fab")
			(effects
				(font
					(size 1.27 1.27)
				)
				(justify mirror)
			)
		)
		(duplicate_pad_numbers_are_jumpers no)
		(fp_line
			(start -0.299974 -0.150114)
			(end -0.299974 0.150114)
			(stroke
				(width 0.1)
				(type default)
			)
			(layer "B.Fab")
		)
		(fp_line
			(start -0.299974 0.150114)
			(end 0.299974 0.150114)
			(stroke
				(width 0.1)
				(type default)
			)
			(layer "B.Fab")
		)
		(fp_line
			(start 0.299974 -0.150114)
			(end -0.299974 -0.150114)
			(stroke
				(width 0.1)
				(type default)
			)
			(layer "B.Fab")
		)
		(fp_line
			(start 0.299974 0.150114)
			(end 0.299974 -0.150114)
			(stroke
				(width 0.1)
				(type default)
			)
			(layer "B.Fab")
		)
		(pad "1" smd rect
			(at 0.2667 0 180)
			(size 0.3048 0.381)
			(layers "B.Cu" "B.Mask" "B.Paste")
			(net "P3E_CPU1_P5_TX_C_DP<1>")
		)
		(pad "2" smd rect
			(at -0.2667 0 180)
			(size 0.3048 0.381)
			(layers "B.Cu" "B.Mask" "B.Paste")
			(net "P3E_CPU1_P5_TX_DP<1>")
		)
	)
	(footprint ""
		(layer "B.Cu")
		(at 393.809728 -200.742804 90)
		(property "Reference" "R6133"
			(at 0 0 90)
			(layer "B.SilkS")
			(hide yes)
			(effects
				(font
					(size 1.27 1.27)
				)
				(justify mirror)
			)
		)
		(property "Value" ""
			(at 0 0 90)
			(layer "B.Fab")
			(effects
				(font
					(size 1.27 1.27)
				)
				(justify mirror)
			)
		)
		(duplicate_pad_numbers_are_jumpers no)
		(fp_line
			(start 0.7874 -0.4064)
			(end -0.7874 -0.4064)
			(stroke
				(width 0.1524)
				(type default)
			)
			(layer "B.SilkS")
		)
		(fp_line
			(start -0.7874 -0.4064)
			(end -0.7874 0.4064)
			(stroke
				(width 0.1524)
				(type default)
			)
			(layer "B.SilkS")
		)
		(fp_line
			(start 0.7874 0.4064)
			(end 0.7874 -0.4064)
			(stroke
				(width 0.1524)
				(type default)
			)
			(layer "B.SilkS")
		)
		(fp_line
			(start -0.7874 0.4064)
			(end 0.7874 0.4064)
			(stroke
				(width 0.1524)
				(type default)
			)
			(layer "B.SilkS")
		)
		(fp_line
			(start 0.67945 -0.305054)
			(end 0.12065 -0.305054)
			(stroke
				(width 0.1)
				(type default)
			)
			(layer "B.Fab")
		)
		(fp_line
			(start 0.12065 -0.305054)
			(end 0.12065 -0.2794)
			(stroke
				(width 0.1)
				(type default)
			)
			(layer "B.Fab")
		)
		(fp_line
			(start -0.12065 -0.3048)
			(end -0.67945 -0.3048)
			(stroke
				(width 0.1)
				(type default)
			)
			(layer "B.Fab")
		)
		(fp_line
			(start -0.67945 -0.3048)
			(end -0.67945 0.3048)
			(stroke
				(width 0.1)
				(type default)
			)
			(layer "B.Fab")
		)
		(fp_line
			(start 0.12065 -0.2794)
			(end -0.12065 -0.2794)
			(stroke
				(width 0.1)
				(type default)
			)
			(layer "B.Fab")
		)
		(fp_line
			(start -0.12065 -0.2794)
			(end -0.12065 -0.3048)
			(stroke
				(width 0.1)
				(type default)
			)
			(layer "B.Fab")
		)
		(fp_line
			(start 0.12065 0.2794)
			(end 0.12065 0.3048)
			(stroke
				(width 0.1)
				(type default)
			)
			(layer "B.Fab")
		)
		(fp_line
			(start -0.120396 0.2794)
			(end 0.12065 0.2794)
			(stroke
				(width 0.1)
				(type default)
			)
			(layer "B.Fab")
		)
		(fp_line
			(start 0.67945 0.3048)
			(end 0.67945 -0.305054)
			(stroke
				(width 0.1)
				(type default)
			)
			(layer "B.Fab")
		)
		(fp_line
			(start 0.12065 0.3048)
			(end 0.67945 0.3048)
			(stroke
				(width 0.1)
				(type default)
			)
			(layer "B.Fab")
		)
		(fp_line
			(start -0.120396 0.3048)
			(end -0.120396 0.2794)
			(stroke
				(width 0.1)
				(type default)
			)
			(layer "B.Fab")
		)
		(fp_line
			(start -0.67945 0.3048)
			(end -0.120396 0.3048)
			(stroke
				(width 0.1)
				(type default)
			)
			(layer "B.Fab")
		)
		(pad "1" smd circle
			(at 0.40005 0 270)
			(size 0 0)
			(layers "B.Cu" "B.Mask" "B.Paste")
			(net "FAB_REV_ID2")
		)
		(pad "2" smd circle
			(at -0.40005 0 270)
			(size 0 0)
			(layers "B.Cu" "B.Mask" "B.Paste")
			(net "GND")
		)
	)
	(footprint ""
		(layer "B.Cu")
		(at 98.578924 -259.73024 180)
		(property "Reference" "C2107"
			(at 0 0 0)
			(layer "B.SilkS")
			(hide yes)
			(effects
				(font
					(size 1.27 1.27)
				)
				(justify mirror)
			)
		)
		(property "Value" ""
			(at 0 0 0)
			(layer "B.Fab")
			(effects
				(font
					(size 1.27 1.27)
				)
				(justify mirror)
			)
		)
		(duplicate_pad_numbers_are_jumpers no)
		(fp_line
			(start 0.7874 0.4064)
			(end 0.7874 -0.4064)
			(stroke
				(width 0.1524)
				(type default)
			)
			(layer "B.SilkS")
		)
		(fp_line
			(start 0.7874 -0.4064)
			(end -0.7874 -0.4064)
			(stroke
				(width 0.1524)
				(type default)
			)
			(layer "B.SilkS")
		)
		(fp_line
			(start -0.7874 0.4064)
			(end 0.7874 0.4064)
			(stroke
				(width 0.1524)
				(type default)
			)
			(layer "B.SilkS")
		)
		(fp_line
			(start -0.7874 -0.4064)
			(end -0.7874 0.4064)
			(stroke
				(width 0.1524)
				(type default)
			)
			(layer "B.SilkS")
		)
		(fp_line
			(start 0.67945 0.3048)
			(end 0.67945 -0.305054)
			(stroke
				(width 0.1)
				(type default)
			)
			(layer "B.Fab")
		)
		(fp_line
			(start 0.67945 -0.305054)
			(end 0.12065 -0.305054)
			(stroke
				(width 0.1)
				(type default)
			)
			(layer "B.Fab")
		)
		(fp_line
			(start 0.12065 0.3048)
			(end 0.67945 0.3048)
			(stroke
				(width 0.1)
				(type default)
			)
			(layer "B.Fab")
		)
		(fp_line
			(start 0.12065 0.2794)
			(end 0.12065 0.3048)
			(stroke
				(width 0.1)
				(type default)
			)
			(layer "B.Fab")
		)
		(fp_line
			(start 0.12065 -0.2794)
			(end -0.12065 -0.2794)
			(stroke
				(width 0.1)
				(type default)
			)
			(layer "B.Fab")
		)
		(fp_line
			(start 0.12065 -0.305054)
			(end 0.12065 -0.2794)
			(stroke
				(width 0.1)
				(type default)
			)
			(layer "B.Fab")
		)
		(fp_line
			(start -0.120396 0.3048)
			(end -0.120396 0.2794)
			(stroke
				(width 0.1)
				(type default)
			)
			(layer "B.Fab")
		)
		(fp_line
			(start -0.120396 0.2794)
			(end 0.12065 0.2794)
			(stroke
				(width 0.1)
				(type default)
			)
			(layer "B.Fab")
		)
		(fp_line
			(start -0.12065 -0.2794)
			(end -0.12065 -0.3048)
			(stroke
				(width 0.1)
				(type default)
			)
			(layer "B.Fab")
		)
		(fp_line
			(start -0.12065 -0.3048)
			(end -0.67945 -0.3048)
			(stroke
				(width 0.1)
				(type default)
			)
			(layer "B.Fab")
		)
		(fp_line
			(start -0.67945 0.3048)
			(end -0.120396 0.3048)
			(stroke
				(width 0.1)
				(type default)
			)
			(layer "B.Fab")
		)
		(fp_line
			(start -0.67945 -0.3048)
			(end -0.67945 0.3048)
			(stroke
				(width 0.1)
				(type default)
			)
			(layer "B.Fab")
		)
		(pad "1" smd circle
			(at 0.40005 0)
			(size 0 0)
			(layers "B.Cu" "B.Mask" "B.Paste")
			(net "PVDDIO_P1")
		)
		(pad "2" smd circle
			(at -0.40005 0)
			(size 0 0)
			(layers "B.Cu" "B.Mask" "B.Paste")
			(net "GND")
		)
	)
)
